(kicad_pcb
	(version 20241229)
	(generator "pcbnew")
	(generator_version "9.0")
	(general
		(thickness 1.599998)
		(legacy_teardrops no)
	)
	(paper "A4")
	(title_block
		(date "2023-02-12")
		(rev "1.1.5")
		(comment 9 "footprints 310-315 of 473")
	)
	(layers
		(0 "F.Cu" signal)
		(4 "In1.Cu" power "In1.GND")
		(6 "In2.Cu" signal)
		(8 "In3.Cu" power "In3.GND")
		(10 "In4.Cu" power "In4.VCC")
		(12 "In5.Cu" signal)
		(14 "In6.Cu" power "In6.VCC")
		(2 "B.Cu" signal)
		(9 "F.Adhes" user "F.Adhesive")
		(11 "B.Adhes" user "B.Adhesive")
		(13 "F.Paste" user)
		(15 "B.Paste" user)
		(5 "F.SilkS" user "F.Silkscreen")
		(7 "B.SilkS" user "B.Silkscreen")
		(1 "F.Mask" user)
		(3 "B.Mask" user)
		(17 "Dwgs.User" user "User.Drawings")
		(19 "Cmts.User" user "User.Comments")
		(21 "Eco1.User" user "User.Eco1")
		(23 "Eco2.User" user "User.Eco2")
		(25 "Edge.Cuts" user)
		(27 "Margin" user)
		(31 "F.CrtYd" user "F.Courtyard")
		(29 "B.CrtYd" user "B.Courtyard")
		(35 "F.Fab" user)
		(33 "B.Fab" user)
	)
	(footprint "antmicro-footprints:C_0402_1005Metric"
		(layer "F.Cu")
		(at 111.94 99.449 180)
		(descr "Capacitor SMD 0402")
		(tags "capacitor SMD 0402")
		(property "Reference" "C162"
			(at 3.64 -0.351 180)
			(layer "F.SilkS")
			(effects
				(font
					(size 0.7 0.7)
					(thickness 0.15)
				)
				(justify left bottom)
			)
		)
		(property "Value" "C_1u_0402"
			(at 0 1.4 180)
			(layer "F.Fab")
			(effects
				(font
					(size 0.7 0.7)
					(thickness 0.15)
				)
				(justify left bottom)
			)
		)
		(property "Description" " "
			(at 0 0 180)
			(layer "F.Fab")
			(hide yes)
			(effects
				(font
					(size 1.27 1.27)
					(thickness 0.15)
				)
			)
		)
		(property "Author" "Antmicro"
			(at 223.88 198.898 0)
			(layer "F.Fab")
			(hide yes)
			(effects
				(font
					(size 1 1)
					(thickness 0.15)
				)
			)
		)
		(property "Dielectric" ""
			(at 223.88 198.898 0)
			(layer "F.Fab")
			(hide yes)
			(effects
				(font
					(size 1 1)
					(thickness 0.15)
				)
			)
		)
		(property "License" "Apache-2.0"
			(at 223.88 198.898 0)
			(layer "F.Fab")
			(hide yes)
			(effects
				(font
					(size 1 1)
					(thickness 0.15)
				)
			)
		)
		(property "MPN" "C1005X6S1A105K050BC"
			(at 223.88 198.898 0)
			(layer "F.Fab")
			(hide yes)
			(effects
				(font
					(size 1 1)
					(thickness 0.15)
				)
			)
		)
		(property "Manufacturer" "TDK"
			(at 223.88 198.898 0)
			(layer "F.Fab")
			(hide yes)
			(effects
				(font
					(size 1 1)
					(thickness 0.15)
				)
			)
		)
		(property "Val" "1u"
			(at 223.88 198.898 0)
			(layer "F.Fab")
			(hide yes)
			(effects
				(font
					(size 1 1)
					(thickness 0.15)
				)
			)
		)
		(property "Voltage" ""
			(at 223.88 198.898 0)
			(layer "F.Fab")
			(hide yes)
			(effects
				(font
					(size 1 1)
					(thickness 0.15)
				)
			)
		)
		(sheetname "Supply")
		(sheetfile "supply.kicad_sch")
		(attr smd)
		(fp_rect
			(start -0.94 -0.47)
			(end 0.94 0.47)
			(stroke
				(width 0.05)
				(type solid)
			)
			(fill no)
			(layer "F.CrtYd")
		)
		(fp_rect
			(start -0.499 -0.249)
			(end 0.499 0.249)
			(stroke
				(width 0.15)
				(type solid)
			)
			(fill no)
			(layer "F.Fab")
		)
		(pad "1" smd roundrect
			(at -0.484 0 180)
			(size 0.59 0.64)
			(layers "F.Cu" "F.Mask" "F.Paste")
			(roundrect_rratio 0.25)
			(net 609 "/Supply/3V3_VCC_INT")
			(pintype "passive")
		)
		(pad "2" smd roundrect
			(at 0.484 0 180)
			(size 0.59 0.64)
			(layers "F.Cu" "F.Mask" "F.Paste")
			(roundrect_rratio 0.25)
			(net 5 "GND")
			(pintype "passive")
		)
	)
	(footprint "antmicro-footprints:C_0603_1608Metric"
		(layer "F.Cu")
		(at 125.3 59.85 180)
		(descr "Capacitor SMD 0603")
		(tags "capacitor 0603")
		(property "Reference" "C183"
			(at 3.9 -0.35 180)
			(layer "F.SilkS")
			(effects
				(font
					(size 0.7 0.7)
					(thickness 0.15)
				)
				(justify left bottom)
			)
		)
		(property "Value" "C_100n_0603"
			(at 0 1.6 180)
			(layer "F.Fab")
			(effects
				(font
					(size 0.7 0.7)
					(thickness 0.15)
				)
				(justify left bottom)
			)
		)
		(property "Description" " "
			(at 0 0 180)
			(layer "F.Fab")
			(hide yes)
			(effects
				(font
					(size 1.27 1.27)
					(thickness 0.15)
				)
			)
		)
		(property "Author" "Antmicro"
			(at 250.6 119.7 0)
			(layer "F.Fab")
			(hide yes)
			(effects
				(font
					(size 1 1)
					(thickness 0.15)
				)
			)
		)
		(property "Dielectric" ""
			(at 250.6 119.7 0)
			(layer "F.Fab")
			(hide yes)
			(effects
				(font
					(size 1 1)
					(thickness 0.15)
				)
			)
		)
		(property "License" "Apache-2.0"
			(at 250.6 119.7 0)
			(layer "F.Fab")
			(hide yes)
			(effects
				(font
					(size 1 1)
					(thickness 0.15)
				)
			)
		)
		(property "MPN" "0603YC104KAZ2A"
			(at 250.6 119.7 0)
			(layer "F.Fab")
			(hide yes)
			(effects
				(font
					(size 1 1)
					(thickness 0.15)
				)
			)
		)
		(property "Manufacturer" "AVX"
			(at 250.6 119.7 0)
			(layer "F.Fab")
			(hide yes)
			(effects
				(font
					(size 1 1)
					(thickness 0.15)
				)
			)
		)
		(property "Val" "100n"
			(at 250.6 119.7 0)
			(layer "F.Fab")
			(hide yes)
			(effects
				(font
					(size 1 1)
					(thickness 0.15)
				)
			)
		)
		(property "Voltage" ""
			(at 250.6 119.7 0)
			(layer "F.Fab")
			(hide yes)
			(effects
				(font
					(size 1 1)
					(thickness 0.15)
				)
			)
		)
		(sheetname "Supply")
		(sheetfile "supply.kicad_sch")
		(attr exclude_from_pos_files exclude_from_bom dnp)
		(fp_line
			(start -0.3 0.3)
			(end 0.3 0.3)
			(stroke
				(width 0.15)
				(type solid)
			)
			(layer "F.SilkS")
		)
		(fp_line
			(start -0.3 -0.3)
			(end 0.3 -0.3)
			(stroke
				(width 0.15)
				(type solid)
			)
			(layer "F.SilkS")
		)
		(fp_rect
			(start -1.24 -0.7)
			(end 1.24 0.7)
			(stroke
				(width 0.05)
				(type solid)
			)
			(fill no)
			(layer "F.CrtYd")
		)
		(fp_rect
			(start -0.8 -0.4)
			(end 0.8 0.4)
			(stroke
				(width 0.15)
				(type solid)
			)
			(fill no)
			(layer "F.Fab")
		)
		(pad "1" smd roundrect
			(at -0.7 0 180)
			(size 0.6 0.8)
			(layers "F.Cu" "F.Mask" "F.Paste")
			(roundrect_rratio 0.2)
			(net 463 "VCC5V0_INT")
			(pintype "passive")
		)
		(pad "2" smd roundrect
			(at 0.7 0 180)
			(size 0.6 0.8)
			(layers "F.Cu" "F.Mask" "F.Paste")
			(roundrect_rratio 0.2)
			(net 5 "GND")
			(pintype "passive")
		)
	)
	(footprint "antmicro-footprints:C_0603_1608Metric"
		(layer "F.Cu")
		(at 128.6 68.3 180)
		(descr "Capacitor SMD 0603")
		(tags "capacitor 0603")
		(property "Reference" "C193"
			(at 3.9 -0.4 180)
			(layer "F.SilkS")
			(effects
				(font
					(size 0.7 0.7)
					(thickness 0.15)
				)
				(justify left bottom)
			)
		)
		(property "Value" "C_22u_0603"
			(at 0 1.6 180)
			(layer "F.Fab")
			(effects
				(font
					(size 0.7 0.7)
					(thickness 0.15)
				)
				(justify left bottom)
			)
		)
		(property "Description" " "
			(at 0 0 180)
			(layer "F.Fab")
			(hide yes)
			(effects
				(font
					(size 1.27 1.27)
					(thickness 0.15)
				)
			)
		)
		(property "Author" "Antmicro"
			(at 257.2 136.6 0)
			(layer "F.Fab")
			(hide yes)
			(effects
				(font
					(size 1 1)
					(thickness 0.15)
				)
			)
		)
		(property "Dielectric" ""
			(at 257.2 136.6 0)
			(layer "F.Fab")
			(hide yes)
			(effects
				(font
					(size 1 1)
					(thickness 0.15)
				)
			)
		)
		(property "License" "Apache-2.0"
			(at 257.2 136.6 0)
			(layer "F.Fab")
			(hide yes)
			(effects
				(font
					(size 1 1)
					(thickness 0.15)
				)
			)
		)
		(property "MPN" "GRM188R60J226MEA0D"
			(at 257.2 136.6 0)
			(layer "F.Fab")
			(hide yes)
			(effects
				(font
					(size 1 1)
					(thickness 0.15)
				)
			)
		)
		(property "Manufacturer" "Murata"
			(at 257.2 136.6 0)
			(layer "F.Fab")
			(hide yes)
			(effects
				(font
					(size 1 1)
					(thickness 0.15)
				)
			)
		)
		(property "Val" "22u"
			(at 257.2 136.6 0)
			(layer "F.Fab")
			(hide yes)
			(effects
				(font
					(size 1 1)
					(thickness 0.15)
				)
			)
		)
		(property "Voltage" ""
			(at 257.2 136.6 0)
			(layer "F.Fab")
			(hide yes)
			(effects
				(font
					(size 1 1)
					(thickness 0.15)
				)
			)
		)
		(sheetname "Supply")
		(sheetfile "supply.kicad_sch")
		(attr exclude_from_pos_files exclude_from_bom dnp)
		(fp_line
			(start -0.3 0.3)
			(end 0.3 0.3)
			(stroke
				(width 0.15)
				(type solid)
			)
			(layer "F.SilkS")
		)
		(fp_line
			(start -0.3 -0.3)
			(end 0.3 -0.3)
			(stroke
				(width 0.15)
				(type solid)
			)
			(layer "F.SilkS")
		)
		(fp_rect
			(start -1.24 -0.7)
			(end 1.24 0.7)
			(stroke
				(width 0.05)
				(type solid)
			)
			(fill no)
			(layer "F.CrtYd")
		)
		(fp_rect
			(start -0.8 -0.4)
			(end 0.8 0.4)
			(stroke
				(width 0.15)
				(type solid)
			)
			(fill no)
			(layer "F.Fab")
		)
		(pad "1" smd roundrect
			(at -0.7 0 180)
			(size 0.6 0.8)
			(layers "F.Cu" "F.Mask" "F.Paste")
			(roundrect_rratio 0.2)
			(net 551 "/Supply/VDD1V8")
			(pintype "passive")
		)
		(pad "2" smd roundrect
			(at 0.7 0 180)
			(size 0.6 0.8)
			(layers "F.Cu" "F.Mask" "F.Paste")
			(roundrect_rratio 0.2)
			(net 5 "GND")
			(pintype "passive")
		)
	)
	(footprint "antmicro-footprints:L_2020_5252Metric"
		(layer "F.Cu")
		(at 130.3 62.475 -90)
		(property "Reference" "L7"
			(at -3.275 -1.6 0)
			(layer "F.SilkS")
			(effects
				(font
					(size 0.7 0.7)
					(thickness 0.15)
				)
				(justify left bottom)
			)
		)
		(property "Value" "L_4u7_2.8A_2020"
			(at 0 4 270)
			(layer "F.Fab")
			(effects
				(font
					(size 0.7 0.7)
					(thickness 0.15)
				)
				(justify left bottom)
			)
		)
		(property "Author" "Antmicro"
			(at 67.825 192.775 0)
			(layer "F.Fab")
			(hide yes)
			(effects
				(font
					(size 1 1)
					(thickness 0.15)
				)
			)
		)
		(property "IMax" ""
			(at 67.825 192.775 0)
			(layer "F.Fab")
			(hide yes)
			(effects
				(font
					(size 1 1)
					(thickness 0.15)
				)
			)
		)
		(property "ISat" ""
			(at 67.825 192.775 0)
			(layer "F.Fab")
			(hide yes)
			(effects
				(font
					(size 1 1)
					(thickness 0.15)
				)
			)
		)
		(property "License" "Apache-2.0"
			(at 67.825 192.775 0)
			(layer "F.Fab")
			(hide yes)
			(effects
				(font
					(size 1 1)
					(thickness 0.15)
				)
			)
		)
		(property "MPN" "IHLP2020BZER4R7M01"
			(at 67.825 192.775 0)
			(layer "F.Fab")
			(hide yes)
			(effects
				(font
					(size 1 1)
					(thickness 0.15)
				)
			)
		)
		(property "Manufacturer" "Vishay"
			(at 67.825 192.775 0)
			(layer "F.Fab")
			(hide yes)
			(effects
				(font
					(size 1 1)
					(thickness 0.15)
				)
			)
		)
		(property "Size" "5.18x5.18"
			(at 67.825 192.775 0)
			(layer "F.Fab")
			(hide yes)
			(effects
				(font
					(size 1 1)
					(thickness 0.15)
				)
			)
		)
		(property "Val" "4u7/2.8A"
			(at 67.825 192.775 0)
			(layer "F.Fab")
			(hide yes)
			(effects
				(font
					(size 1 1)
					(thickness 0.15)
				)
			)
		)
		(sheetname "Supply")
		(sheetfile "supply.kicad_sch")
		(attr exclude_from_pos_files exclude_from_bom dnp)
		(fp_line
			(start -2.999 2.843)
			(end 2.996 2.843)
			(stroke
				(width 0.15)
				(type solid)
			)
			(layer "F.SilkS")
		)
		(fp_line
			(start 2.996 2.843)
			(end 2.996 1.729)
			(stroke
				(width 0.15)
				(type solid)
			)
			(layer "F.SilkS")
		)
		(fp_line
			(start -2.999 1.729)
			(end -2.999 2.843)
			(stroke
				(width 0.15)
				(type solid)
			)
			(layer "F.SilkS")
		)
		(fp_line
			(start 2.996 -1.73)
			(end 2.996 -2.846)
			(stroke
				(width 0.15)
				(type solid)
			)
			(layer "F.SilkS")
		)
		(fp_line
			(start -2.999 -2.846)
			(end -2.999 -1.73)
			(stroke
				(width 0.15)
				(type solid)
			)
			(layer "F.SilkS")
		)
		(fp_line
			(start 2.996 -2.846)
			(end -2.999 -2.846)
			(stroke
				(width 0.15)
				(type solid)
			)
			(layer "F.SilkS")
		)
		(fp_line
			(start -3.13 2.97)
			(end -3.13 1.65)
			(stroke
				(width 0.05)
				(type solid)
			)
			(layer "F.CrtYd")
		)
		(fp_line
			(start 3.12 2.97)
			(end -3.13 2.97)
			(stroke
				(width 0.05)
				(type solid)
			)
			(layer "F.CrtYd")
		)
		(fp_line
			(start -3.29 1.65)
			(end -3.29 -1.67)
			(stroke
				(width 0.05)
				(type solid)
			)
			(layer "F.CrtYd")
		)
		(fp_line
			(start -3.13 1.65)
			(end -3.29 1.65)
			(stroke
				(width 0.05)
				(type solid)
			)
			(layer "F.CrtYd")
		)
		(fp_line
			(start 3.12 1.65)
			(end 3.12 2.97)
			(stroke
				(width 0.05)
				(type solid)
			)
			(layer "F.CrtYd")
		)
		(fp_line
			(start 3.26 1.65)
			(end 3.12 1.65)
			(stroke
				(width 0.05)
				(type solid)
			)
			(layer "F.CrtYd")
		)
		(fp_line
			(start -3.29 -1.67)
			(end -3.13 -1.67)
			(stroke
				(width 0.05)
				(type solid)
			)
			(layer "F.CrtYd")
		)
		(fp_line
			(start -3.13 -1.67)
			(end -3.13 -2.98)
			(stroke
				(width 0.05)
				(type solid)
			)
			(layer "F.CrtYd")
		)
		(fp_line
			(start 3.12 -1.67)
			(end 3.26 -1.67)
			(stroke
				(width 0.05)
				(type solid)
			)
			(layer "F.CrtYd")
		)
		(fp_line
			(start 3.26 -1.67)
			(end 3.26 1.65)
			(stroke
				(width 0.05)
				(type solid)
			)
			(layer "F.CrtYd")
		)
		(fp_line
			(start -3.13 -2.98)
			(end 3.12 -2.98)
			(stroke
				(width 0.05)
				(type solid)
			)
			(layer "F.CrtYd")
		)
		(fp_line
			(start 3.12 -2.98)
			(end 3.12 -1.67)
			(stroke
				(width 0.05)
				(type solid)
			)
			(layer "F.CrtYd")
		)
		(fp_line
			(start -2.871 2.717)
			(end 2.87 2.717)
			(stroke
				(width 0.15)
				(type solid)
			)
			(layer "F.Fab")
		)
		(fp_line
			(start 2.87 2.717)
			(end 2.87 -2.718)
			(stroke
				(width 0.15)
				(type solid)
			)
			(layer "F.Fab")
		)
		(fp_line
			(start -2.871 -2.718)
			(end -2.871 2.717)
			(stroke
				(width 0.15)
				(type solid)
			)
			(layer "F.Fab")
		)
		(fp_line
			(start 2.87 -2.718)
			(end -2.871 -2.718)
			(stroke
				(width 0.15)
				(type solid)
			)
			(layer "F.Fab")
		)
		(pad "1" smd rect
			(at -2.032 0)
			(size 2.794 1.9812)
			(layers "F.Cu" "F.Mask" "F.Paste")
			(net 628 "/Supply/VDD1_SW")
			(pintype "passive")
		)
		(pad "2" smd rect
			(at 2.031 0)
			(size 2.794 1.9812)
			(layers "F.Cu" "F.Mask" "F.Paste")
			(net 551 "/Supply/VDD1V8")
			(pintype "passive")
		)
	)
	(footprint "antmicro-footprints:R_0402_1005Metric"
		(layer "F.Cu")
		(at 135.6 59.7)
		(descr "Resistor SMD 0402")
		(tags "resistor SMD 0402")
		(property "Reference" "R148"
			(at -1.9 -0.5 0)
			(layer "F.SilkS")
			(effects
				(font
					(size 0.7 0.7)
					(thickness 0.15)
				)
				(justify left bottom)
			)
		)
		(property "Value" "R_10k_0402"
			(at 0 1.4 0)
			(layer "F.Fab")
			(effects
				(font
					(size 0.7 0.7)
					(thickness 0.15)
				)
				(justify left bottom)
			)
		)
		(property "Description" "10k resistor in 0402 package with 1% tolerance"
			(at 0 0 0)
			(layer "F.Fab")
			(hide yes)
			(effects
				(font
					(size 1.27 1.27)
					(thickness 0.15)
				)
			)
		)
		(property "Author" "Antmicro"
			(at 0 0 0)
			(layer "F.Fab")
			(hide yes)
			(effects
				(font
					(size 1 1)
					(thickness 0.15)
				)
			)
		)
		(property "License" "Apache-2.0"
			(at 0 0 0)
			(layer "F.Fab")
			(hide yes)
			(effects
				(font
					(size 1 1)
					(thickness 0.15)
				)
			)
		)
		(property "MPN" "CR0402-FX-1002GLF"
			(at 0 0 0)
			(layer "F.Fab")
			(hide yes)
			(effects
				(font
					(size 1 1)
					(thickness 0.15)
				)
			)
		)
		(property "Manufacturer" "Bourns"
			(at 0 0 0)
			(layer "F.Fab")
			(hide yes)
			(effects
				(font
					(size 1 1)
					(thickness 0.15)
				)
			)
		)
		(property "Tolerance" "1%"
			(at 0 0 0)
			(layer "F.Fab")
			(hide yes)
			(effects
				(font
					(size 1 1)
					(thickness 0.15)
				)
			)
		)
		(property "Val" "10k"
			(at 0 0 0)
			(layer "F.Fab")
			(hide yes)
			(effects
				(font
					(size 1 1)
					(thickness 0.15)
				)
			)
		)
		(sheetname "Supply")
		(sheetfile "supply.kicad_sch")
		(attr smd)
		(fp_rect
			(start -0.93 -0.47)
			(end 0.93 0.47)
			(stroke
				(width 0.05)
				(type solid)
			)
			(fill no)
			(layer "F.CrtYd")
		)
		(fp_rect
			(start -0.5 -0.25)
			(end 0.5 0.25)
			(stroke
				(width 0.15)
				(type solid)
			)
			(fill no)
			(layer "F.Fab")
		)
		(pad "1" smd roundrect
			(at -0.485 0)
			(size 0.59 0.64)
			(layers "F.Cu" "F.Mask" "F.Paste")
			(roundrect_rratio 0.25)
			(net 470 "/Supply/VCC_IO_EN")
			(pintype "passive")
		)
		(pad "2" smd roundrect
			(at 0.485 0)
			(size 0.59 0.64)
			(layers "F.Cu" "F.Mask" "F.Paste")
			(roundrect_rratio 0.25)
			(net 636 "/Supply/0V6_EN")
			(pintype "passive")
		)
	)
	(footprint "antmicro-footprints:TP_SMD_1mm"
		(layer "F.Cu")
		(at 170.6 109.9)
		(property "Reference" "TP8"
			(at -2.6 0.4 0)
			(layer "F.SilkS")
			(effects
				(font
					(size 0.7 0.7)
					(thickness 0.15)
				)
				(justify left bottom)
			)
		)
		(property "Value" "TP_1mm_SMD"
			(at 0 1.4 0)
			(layer "F.Fab")
			(effects
				(font
					(size 0.7 0.7)
					(thickness 0.15)
				)
				(justify left bottom)
			)
		)
		(property "Description" "Test Point 1mm"
			(at 0 0 0)
			(layer "F.Fab")
			(hide yes)
			(effects
				(font
					(size 1.27 1.27)
					(thickness 0.15)
				)
			)
		)
		(property "Author" "Antmicro"
			(at 0 0 0)
			(layer "F.Fab")
			(hide yes)
			(effects
				(font
					(size 1 1)
					(thickness 0.15)
				)
			)
		)
		(property "License" "Apache-2.0"
			(at 0 0 0)
			(layer "F.Fab")
			(hide yes)
			(effects
				(font
					(size 1 1)
					(thickness 0.15)
				)
			)
		)
		(property "MPN" ""
			(at 0 0 0)
			(layer "F.Fab")
			(hide yes)
			(effects
				(font
					(size 1 1)
					(thickness 0.15)
				)
			)
		)
		(property "Manufacturer" ""
			(at 0 0 0)
			(layer "F.Fab")
			(hide yes)
			(effects
				(font
					(size 1 1)
					(thickness 0.15)
				)
			)
		)
		(sheetname "Config SPI flash")
		(sheetfile "config-spi.kicad_sch")
		(attr exclude_from_pos_files)
		(pad "1" smd circle
			(at 0 0)
			(size 1 1)
			(layers "F.Cu" "F.Mask")
			(net 217 "EMCCLK")
			(pinfunction "1")
			(pintype "passive")
		)
	)
)
